(kicad_pcb
	(version 20241229)
	(generator "pcbnew")
	(generator_version "9.0")
	(general
		(thickness 1.62)
		(legacy_teardrops no)
	)
	(paper "A3")
	(title_block
		(title "COM Express 7 Baseboard")
		(date "2025-02-04")
		(rev "1.1.2")
		(company "Antmicro Ltd")
		(comment 1 "www.antmicro.com")
		(comment 9 "footprints 412-415 of 802")
	)
	(layers
		(0 "F.Cu" signal)
		(4 "In1.Cu" signal)
		(6 "In2.Cu" signal)
		(8 "In3.Cu" signal)
		(10 "In4.Cu" signal)
		(12 "In5.Cu" signal)
		(14 "In6.Cu" signal)
		(2 "B.Cu" signal)
		(9 "F.Adhes" user "F.Adhesive")
		(11 "B.Adhes" user "B.Adhesive")
		(13 "F.Paste" user)
		(15 "B.Paste" user)
		(5 "F.SilkS" user "F.Silkscreen")
		(7 "B.SilkS" user "B.Silkscreen")
		(1 "F.Mask" user)
		(3 "B.Mask" user)
		(17 "Dwgs.User" user "User.Drawings")
		(19 "Cmts.User" user "User.Comments")
		(21 "Eco1.User" user "User.Eco1")
		(23 "Eco2.User" user "User.Eco2")
		(25 "Edge.Cuts" user)
		(27 "Margin" user)
		(31 "F.CrtYd" user "F.Courtyard")
		(29 "B.CrtYd" user "B.Courtyard")
		(35 "F.Fab" user)
		(33 "B.Fab" user)
	)
	(footprint "antmicro-footprints:USON-10_2.5x1mm_P0.5mm"
		(layer "F.Cu")
		(at 314.75 163.96)
		(descr "USON-10 2.5x1mm_ Pitch 0.5mm")
		(tags "USON-10 2.5x1mm Pitch 0.5mm")
		(property "Reference" "U12"
			(at -0.9 1.1 270)
			(layer "F.SilkS")
			(effects
				(font
					(size 0.7 0.7)
					(thickness 0.15)
				)
				(justify left bottom)
			)
		)
		(property "Value" "ESD204DQAR"
			(at 0.018 2.499 0)
			(layer "F.Fab")
			(effects
				(font
					(size 0.7 0.7)
					(thickness 0.15)
				)
				(justify left bottom)
			)
		)
		(property "Datasheet" "https://www.ti.com/lit/ds/symlink/esd204.pdf?ts=1706004844383&ref_url=https%253A%252F%252Fwww.ti.com%252Finterface%252Fdiodes%252Fesd-protection-diodes%252Fproducts.html"
			(at 0 0 0)
			(layer "F.Fab")
			(hide yes)
			(effects
				(font
					(size 1.27 1.27)
					(thickness 0.15)
				)
			)
		)
		(property "Author" "Antmicro"
			(at 0 0 0)
			(layer "F.Fab")
			(hide yes)
			(effects
				(font
					(size 1 1)
					(thickness 0.15)
				)
			)
		)
		(property "License" "Apache-2.0"
			(at 0 0 0)
			(layer "F.Fab")
			(hide yes)
			(effects
				(font
					(size 1 1)
					(thickness 0.15)
				)
			)
		)
		(property "MPN" "ESD204DQAR"
			(at 0 0 0)
			(layer "F.Fab")
			(hide yes)
			(effects
				(font
					(size 1 1)
					(thickness 0.15)
				)
			)
		)
		(property "Manufacturer" "Texas Instruments"
			(at 0 0 0)
			(layer "F.Fab")
			(hide yes)
			(effects
				(font
					(size 1 1)
					(thickness 0.15)
				)
			)
		)
		(sheetname "Backplane")
		(sheetfile "backplane.kicad_sch")
		(attr smd)
		(fp_line
			(start 0.498 -1.401)
			(end -0.5 -1.401)
			(stroke
				(width 0.15)
				(type solid)
			)
			(layer "F.SilkS")
		)
		(fp_line
			(start 0.498 1.398)
			(end -0.5 1.398)
			(stroke
				(width 0.15)
				(type solid)
			)
			(layer "F.SilkS")
		)
		(fp_circle
			(center -0.68 -1.27)
			(end -0.63 -1.27)
			(stroke
				(width 0.15)
				(type solid)
			)
			(fill yes)
			(layer "F.SilkS")
		)
		(fp_rect
			(start -0.8 -1.5)
			(end 0.8 1.499)
			(stroke
				(width 0.05)
				(type solid)
			)
			(fill no)
			(layer "F.CrtYd")
		)
		(fp_line
			(start -0.5 -1)
			(end -0.5 1.249)
			(stroke
				(width 0.15)
				(type solid)
			)
			(layer "F.Fab")
		)
		(fp_line
			(start -0.5 1.249)
			(end 0.498 1.249)
			(stroke
				(width 0.15)
				(type solid)
			)
			(layer "F.Fab")
		)
		(fp_line
			(start -0.25 -1.25)
			(end -0.5 -1)
			(stroke
				(width 0.15)
				(type solid)
			)
			(layer "F.Fab")
		)
		(fp_line
			(start 0.498 -1.25)
			(end -0.25 -1.25)
			(stroke
				(width 0.15)
				(type solid)
			)
			(layer "F.Fab")
		)
		(fp_line
			(start 0.498 -1.25)
			(end 0.498 1.249)
			(stroke
				(width 0.15)
				(type solid)
			)
			(layer "F.Fab")
		)
		(pad "1" smd roundrect
			(at -0.387 -1 270)
			(size 0.25 0.55)
			(layers "F.Cu" "F.Mask" "F.Paste")
			(roundrect_rratio 0.25)
			(net 202 "unconnected-(U12-Pad1)")
			(pintype "passive+no_connect")
			(teardrops
				(best_length_ratio 0.2)
				(max_length 1)
				(best_width_ratio 0.9)
				(max_width 2)
				(curved_edges yes)
				(filter_ratio 0.9)
				(enabled yes)
				(allow_two_segments yes)
				(prefer_zone_connections yes)
			)
		)
		(pad "2" smd roundrect
			(at -0.387 -0.5 270)
			(size 0.25 0.55)
			(layers "F.Cu" "F.Mask" "F.Paste")
			(roundrect_rratio 0.25)
			(net 528 "/Backplane/~{PERST}")
			(pintype "passive")
			(teardrops
				(best_length_ratio 0.2)
				(max_length 1)
				(best_width_ratio 0.9)
				(max_width 2)
				(curved_edges yes)
				(filter_ratio 0.9)
				(enabled yes)
				(allow_two_segments yes)
				(prefer_zone_connections yes)
			)
		)
		(pad "3" smd roundrect
			(at -0.387 0 270)
			(size 0.4 0.55)
			(layers "F.Cu" "F.Mask" "F.Paste")
			(roundrect_rratio 0.25)
			(net 1 "GND")
			(pintype "power_in")
			(teardrops
				(best_length_ratio 0.2)
				(max_length 1)
				(best_width_ratio 0.9)
				(max_width 2)
				(curved_edges yes)
				(filter_ratio 0.9)
				(enabled yes)
				(allow_two_segments yes)
				(prefer_zone_connections yes)
			)
		)
		(pad "4" smd roundrect
			(at -0.387 0.498 270)
			(size 0.25 0.55)
			(layers "F.Cu" "F.Mask" "F.Paste")
			(roundrect_rratio 0.25)
			(net 526 "/Backplane/~{PRSNT}")
			(pintype "passive")
			(teardrops
				(best_length_ratio 0.2)
				(max_length 1)
				(best_width_ratio 0.9)
				(max_width 2)
				(curved_edges yes)
				(filter_ratio 0.9)
				(enabled yes)
				(allow_two_segments yes)
				(prefer_zone_connections yes)
			)
		)
		(pad "5" smd roundrect
			(at -0.387 0.998 270)
			(size 0.25 0.55)
			(layers "F.Cu" "F.Mask" "F.Paste")
			(roundrect_rratio 0.25)
			(net 527 "/Backplane/GPIO")
			(pintype "passive")
			(teardrops
				(best_length_ratio 0.2)
				(max_length 1)
				(best_width_ratio 0.9)
				(max_width 2)
				(curved_edges yes)
				(filter_ratio 0.9)
				(enabled yes)
				(allow_two_segments yes)
				(prefer_zone_connections yes)
			)
		)
		(pad "6" smd roundrect
			(at 0.385 0.998 270)
			(size 0.25 0.55)
			(layers "F.Cu" "F.Mask" "F.Paste")
			(roundrect_rratio 0.25)
			(net 527 "/Backplane/GPIO")
			(pintype "passive")
			(teardrops
				(best_length_ratio 0.2)
				(max_length 1)
				(best_width_ratio 0.9)
				(max_width 2)
				(curved_edges yes)
				(filter_ratio 0.9)
				(enabled yes)
				(allow_two_segments yes)
				(prefer_zone_connections yes)
			)
		)
		(pad "7" smd roundrect
			(at 0.385 0.498 270)
			(size 0.25 0.55)
			(layers "F.Cu" "F.Mask" "F.Paste")
			(roundrect_rratio 0.25)
			(net 526 "/Backplane/~{PRSNT}")
			(pintype "passive")
			(teardrops
				(best_length_ratio 0.2)
				(max_length 1)
				(best_width_ratio 0.9)
				(max_width 2)
				(curved_edges yes)
				(filter_ratio 0.9)
				(enabled yes)
				(allow_two_segments yes)
				(prefer_zone_connections yes)
			)
		)
		(pad "8" smd roundrect
			(at 0.385 0 270)
			(size 0.4 0.55)
			(layers "F.Cu" "F.Mask" "F.Paste")
			(roundrect_rratio 0.25)
			(net 1 "GND")
			(pintype "passive")
			(teardrops
				(best_length_ratio 0.2)
				(max_length 1)
				(best_width_ratio 0.9)
				(max_width 2)
				(curved_edges yes)
				(filter_ratio 0.9)
				(enabled yes)
				(allow_two_segments yes)
				(prefer_zone_connections yes)
			)
		)
		(pad "9" smd roundrect
			(at 0.385 -0.5 270)
			(size 0.25 0.55)
			(layers "F.Cu" "F.Mask" "F.Paste")
			(roundrect_rratio 0.25)
			(net 528 "/Backplane/~{PERST}")
			(pintype "passive")
			(teardrops
				(best_length_ratio 0.2)
				(max_length 1)
				(best_width_ratio 0.9)
				(max_width 2)
				(curved_edges yes)
				(filter_ratio 0.9)
				(enabled yes)
				(allow_two_segments yes)
				(prefer_zone_connections yes)
			)
		)
		(pad "10" smd roundrect
			(at 0.385 -1 270)
			(size 0.25 0.55)
			(layers "F.Cu" "F.Mask" "F.Paste")
			(roundrect_rratio 0.25)
			(net 993 "unconnected-(U12-Pad1)_1")
			(pintype "passive+no_connect")
			(teardrops
				(best_length_ratio 0.2)
				(max_length 1)
				(best_width_ratio 0.9)
				(max_width 2)
				(curved_edges yes)
				(filter_ratio 0.9)
				(enabled yes)
				(allow_two_segments yes)
				(prefer_zone_connections yes)
			)
		)
	)
	(footprint "antmicro-footprints:R_0402_1005Metric"
		(layer "F.Cu")
		(at 211.28 129.425 180)
		(descr "Resistor SMD 0402")
		(tags "resistor SMD 0402")
		(property "Reference" "R194"
			(at 0.83 -0.735 0)
			(layer "F.SilkS")
			(effects
				(font
					(size 0.7 0.7)
					(thickness 0.15)
				)
				(justify right bottom)
			)
		)
		(property "Value" "R_0R_0402"
			(at -1.011843 1.772047 0)
			(layer "F.Fab")
			(effects
				(font
					(size 0.7 0.7)
					(thickness 0.15)
				)
				(justify right bottom)
			)
		)
		(property "Datasheet" "https://industrial.panasonic.com/cdbs/www-data/pdf/RDA0000/AOA0000C301.pdf"
			(at 0 0 180)
			(layer "F.Fab")
			(hide yes)
			(effects
				(font
					(size 1.27 1.27)
					(thickness 0.15)
				)
			)
		)
		(property "Author" "Antmicro"
			(at 422.56 258.85 0)
			(layer "F.Fab")
			(hide yes)
			(effects
				(font
					(size 1 1)
					(thickness 0.15)
				)
			)
		)
		(property "Current" "1A"
			(at 422.56 258.85 0)
			(layer "F.Fab")
			(hide yes)
			(effects
				(font
					(size 1 1)
					(thickness 0.15)
				)
			)
		)
		(property "License" "Apache-2.0"
			(at 422.56 258.85 0)
			(layer "F.Fab")
			(hide yes)
			(effects
				(font
					(size 1 1)
					(thickness 0.15)
				)
			)
		)
		(property "MPN" "ERJ2GE0R00X"
			(at 422.56 258.85 0)
			(layer "F.Fab")
			(hide yes)
			(effects
				(font
					(size 1 1)
					(thickness 0.15)
				)
			)
		)
		(property "Manufacturer" "Panasonic"
			(at 422.56 258.85 0)
			(layer "F.Fab")
			(hide yes)
			(effects
				(font
					(size 1 1)
					(thickness 0.15)
				)
			)
		)
		(property "Public" "False"
			(at 422.56 258.85 0)
			(layer "F.Fab")
			(hide yes)
			(effects
				(font
					(size 1 1)
					(thickness 0.15)
				)
			)
		)
		(property "Tolerance" ""
			(at 422.56 258.85 0)
			(layer "F.Fab")
			(hide yes)
			(effects
				(font
					(size 1 1)
					(thickness 0.15)
				)
			)
		)
		(property "Val" "0R"
			(at 422.56 258.85 0)
			(layer "F.Fab")
			(hide yes)
			(effects
				(font
					(size 1 1)
					(thickness 0.15)
				)
			)
		)
		(sheetname "PCIe misc")
		(sheetfile "pcie_misc.kicad_sch")
		(attr smd)
		(fp_rect
			(start -0.925 -0.47)
			(end 0.925 0.47)
			(stroke
				(width 0.05)
				(type default)
			)
			(fill no)
			(layer "F.CrtYd")
		)
		(fp_rect
			(start -0.5 -0.25)
			(end 0.5 0.25)
			(stroke
				(width 0.15)
				(type solid)
			)
			(fill no)
			(layer "F.Fab")
		)
		(pad "1" smd roundrect
			(at -0.48 0 180)
			(size 0.59 0.64)
			(layers "F.Cu" "F.Mask" "F.Paste")
			(roundrect_rratio 0.25)
			(net 613 "/PCIe misc/DIF1+")
			(pintype "passive")
			(teardrops
				(best_length_ratio 0.2)
				(max_length 1)
				(best_width_ratio 0.9)
				(max_width 2)
				(curved_edges yes)
				(filter_ratio 0.9)
				(enabled yes)
				(allow_two_segments yes)
				(prefer_zone_connections yes)
			)
		)
		(pad "2" smd roundrect
			(at 0.48 0 180)
			(size 0.59 0.64)
			(layers "F.Cu" "F.Mask" "F.Paste")
			(roundrect_rratio 0.25)
			(net 193 "/OCuLink/PCIe_{REF0}.CK-")
			(pintype "passive")
			(teardrops
				(best_length_ratio 0.2)
				(max_length 1)
				(best_width_ratio 0.9)
				(max_width 2)
				(curved_edges yes)
				(filter_ratio 0.9)
				(enabled yes)
				(allow_two_segments yes)
				(prefer_zone_connections yes)
			)
		)
	)
	(footprint "antmicro-footprints:Conn_Molex_Nano-Fit_1x2_105309-1202"
		(layer "F.Cu")
		(at 306.3 168.79 180)
		(descr "Based on: https://www.molex.com/content/dam/molex/molex-dot-com/products/automated/en-us/salesdrawingpdf/105/105430/1054301202_sd.pdf?inline")
		(property "Reference" "J6"
			(at 4.4 1.79 0)
			(layer "F.SilkS")
			(effects
				(font
					(size 0.7 0.7)
					(thickness 0.15)
				)
				(justify right top)
			)
		)
		(property "Value" "Molex_Nano-Fit_1x2_105309-1202"
			(at 0 3.05 0)
			(layer "F.Fab")
			(effects
				(font
					(size 0.7 0.7)
					(thickness 0.15)
				)
				(justify right top)
			)
		)
		(property "Datasheet" "https://tools.molex.com/pdm_docs/sd/1053092202_sd.pdf"
			(at 0 0 0)
			(layer "F.Fab")
			(hide yes)
			(effects
				(font
					(size 1.27 1.27)
					(thickness 0.15)
				)
			)
		)
		(property "Description" "Pin Header, Power, 2.5 mm, 1 Rows, 2 Contacts, Through Hole Straight, Nano-Fit"
			(at 0 0 0)
			(layer "F.Fab")
			(hide yes)
			(effects
				(font
					(size 1.27 1.27)
					(thickness 0.15)
				)
			)
		)
		(attr through_hole)
		(fp_line
			(start 4.239 -1.74)
			(end 4.239 4.6)
			(stroke
				(width 0.15)
				(type solid)
			)
			(layer "F.SilkS")
		)
		(fp_line
			(start -1.7 4.6)
			(end 4.239 4.6)
			(stroke
				(width 0.15)
				(type solid)
			)
			(layer "F.SilkS")
		)
		(fp_line
			(start -1.7 -1.74)
			(end 4.239 -1.74)
			(stroke
				(width 0.15)
				(type solid)
			)
			(layer "F.SilkS")
		)
		(fp_line
			(start -1.7 -1.74)
			(end -1.7 4.6)
			(stroke
				(width 0.15)
				(type solid)
			)
			(layer "F.SilkS")
		)
		(fp_circle
			(center -2 0.01)
			(end -1.95 0.01)
			(stroke
				(width 0.15)
				(type solid)
			)
			(fill yes)
			(layer "F.SilkS")
		)
		(fp_rect
			(start -2.25 -2.35)
			(end 4.85 5.15)
			(stroke
				(width 0.05)
				(type solid)
			)
			(fill no)
			(layer "F.CrtYd")
		)
		(fp_text user "License: Apache-2.0"
			(at -2.175 6.3 0)
			(layer "F.Fab")
			(effects
				(font
					(size 0.7 0.7)
					(thickness 0.15)
				)
				(justify right top)
			)
		)
		(fp_text user "${REFERENCE}"
			(at -2.175 7.5 0)
			(layer "F.Fab")
			(effects
				(font
					(size 0.7 0.7)
					(thickness 0.15)
				)
				(justify right top)
			)
		)
		(fp_text user "Author: Antmicro"
			(at -2.175 8.7 0)
			(layer "F.Fab")
			(effects
				(font
					(size 0.7 0.7)
					(thickness 0.15)
				)
				(justify right top)
			)
		)
		(pad "" np_thru_hole circle
			(at 1.25 1.34 180)
			(size 1.3 1.3)
			(drill 1.3)
			(layers "*.Cu" "*.Mask")
		)
		(pad "1" thru_hole circle
			(at 0 0 180)
			(size 2 2)
			(drill 1.3)
			(layers "*.Cu" "*.Mask")
			(remove_unused_layers no)
			(pintype "input")
		)
		(pad "2" thru_hole circle
			(at 2.5 0 180)
			(size 2 2)
			(drill 1.3)
			(layers "*.Cu" "*.Mask")
			(remove_unused_layers no)
			(pintype "input")
		)
	)
	(footprint "antmicro-footprints:C_0402_1005Metric"
		(layer "F.Cu")
		(at 300.55 118.36 90)
		(descr "Capacitor SMD 0402")
		(tags "capacitor SMD 0402")
		(property "Reference" "C56"
			(at -1.05 -0.5 90)
			(layer "F.SilkS")
			(effects
				(font
					(size 0.7 0.7)
					(thickness 0.15)
				)
				(justify left bottom)
			)
		)
		(property "Value" "C_1u_0402"
			(at -1.022927 2.155213 90)
			(layer "F.Fab")
			(effects
				(font
					(size 0.7 0.7)
					(thickness 0.15)
				)
				(justify left bottom)
			)
		)
		(property "Datasheet" "https://product.tdk.com/en/search/capacitor/ceramic/mlcc/info?part_no=C1005X6S1A105K050BC"
			(at 0 0 90)
			(layer "F.Fab")
			(hide yes)
			(effects
				(font
					(size 1.27 1.27)
					(thickness 0.15)
				)
			)
		)
		(property "Author" "Antmicro"
			(at 418.91 -182.19 0)
			(layer "F.Fab")
			(hide yes)
			(effects
				(font
					(size 1 1)
					(thickness 0.15)
				)
			)
		)
		(property "Dielectric" ""
			(at 418.91 -182.19 0)
			(layer "F.Fab")
			(hide yes)
			(effects
				(font
					(size 1 1)
					(thickness 0.15)
				)
			)
		)
		(property "License" "Apache-2.0"
			(at 418.91 -182.19 0)
			(layer "F.Fab")
			(hide yes)
			(effects
				(font
					(size 1 1)
					(thickness 0.15)
				)
			)
		)
		(property "MPN" "C1005X6S1A105K050BC"
			(at 418.91 -182.19 0)
			(layer "F.Fab")
			(hide yes)
			(effects
				(font
					(size 1 1)
					(thickness 0.15)
				)
			)
		)
		(property "Manufacturer" "TDK"
			(at 418.91 -182.19 0)
			(layer "F.Fab")
			(hide yes)
			(effects
				(font
					(size 1 1)
					(thickness 0.15)
				)
			)
		)
		(property "Public" "False"
			(at 418.91 -182.19 0)
			(layer "F.Fab")
			(hide yes)
			(effects
				(font
					(size 1 1)
					(thickness 0.15)
				)
			)
		)
		(property "Val" "1u"
			(at 418.91 -182.19 0)
			(layer "F.Fab")
			(hide yes)
			(effects
				(font
					(size 1 1)
					(thickness 0.15)
				)
			)
		)
		(property "Voltage" ""
			(at 418.91 -182.19 0)
			(layer "F.Fab")
			(hide yes)
			(effects
				(font
					(size 1 1)
					(thickness 0.15)
				)
			)
		)
		(sheetname "Power")
		(sheetfile "power.kicad_sch")
		(attr smd)
		(fp_rect
			(start -0.925 -0.47)
			(end 0.925 0.47)
			(stroke
				(width 0.05)
				(type default)
			)
			(fill no)
			(layer "F.CrtYd")
		)
		(fp_line
			(start 0.504 -0.25)
			(end 0.504 0.248)
			(stroke
				(width 0.15)
				(type solid)
			)
			(layer "F.Fab")
		)
		(fp_line
			(start -0.494 -0.25)
			(end 0.504 -0.25)
			(stroke
				(width 0.15)
				(type solid)
			)
			(layer "F.Fab")
		)
		(fp_line
			(start 0.504 0.248)
			(end -0.494 0.248)
			(stroke
				(width 0.15)
				(type solid)
			)
			(layer "F.Fab")
		)
		(fp_line
			(start -0.494 0.248)
			(end -0.494 -0.25)
			(stroke
				(width 0.15)
				(type solid)
			)
			(layer "F.Fab")
		)
		(pad "1" smd roundrect
			(at -0.48 0 90)
			(size 0.59 0.64)
			(layers "F.Cu" "F.Mask" "F.Paste")
			(roundrect_rratio 0.25)
			(net 1 "GND")
			(pintype "passive")
			(teardrops
				(best_length_ratio 0.2)
				(max_length 1)
				(best_width_ratio 0.9)
				(max_width 2)
				(curved_edges yes)
				(filter_ratio 0.9)
				(enabled yes)
				(allow_two_segments yes)
				(prefer_zone_connections yes)
			)
		)
		(pad "2" smd roundrect
			(at 0.48 0 90)
			(size 0.59 0.64)
			(layers "F.Cu" "F.Mask" "F.Paste")
			(roundrect_rratio 0.25)
			(net 74 "+1V0")
			(pintype "passive")
			(teardrops
				(best_length_ratio 0.2)
				(max_length 1)
				(best_width_ratio 0.9)
				(max_width 2)
				(curved_edges yes)
				(filter_ratio 0.9)
				(enabled yes)
				(allow_two_segments yes)
				(prefer_zone_connections yes)
			)
		)
	)
)
